(kicad_pcb
	(version 20260206)
	(generator "pcbnew")
	(generator_version "10.0")
	(general
		(thickness 1.6)
		(legacy_teardrops no)
	)
	(paper "A4")
	(title_block
		(title "04192023_DAF0TMB3IC0_F0TG_MB_C_brd_V02_OCP.brd")
		(comment 1 "Grand Teton / footprint 3955 of 8354 (U25), pads 5668-5776 of 6102")
	)
	(layers
		(0 "F.Cu" signal "TOP")
		(4 "In1.Cu" signal "GND")
		(6 "In2.Cu" signal "IN1")
		(8 "In3.Cu" signal "GND1")
		(10 "In4.Cu" signal "IN2")
		(12 "In5.Cu" signal "GND2")
		(14 "In6.Cu" signal "IN3")
		(16 "In7.Cu" signal "GND3")
		(18 "In8.Cu" signal "VCC")
		(20 "In9.Cu" signal "VCC1")
		(22 "In10.Cu" signal "GND4")
		(24 "In11.Cu" signal "IN4")
		(26 "In12.Cu" signal "GND5")
		(28 "In13.Cu" signal "IN5")
		(30 "In14.Cu" signal "GND6")
		(32 "In15.Cu" signal "IN6")
		(34 "In16.Cu" signal "GND7")
		(2 "B.Cu" signal "BOTTOM")
		(9 "F.Adhes" user "F.Adhesive")
		(11 "B.Adhes" user "B.Adhesive")
		(13 "F.Paste" user "Package Geometry/Pastemask Top")
		(15 "B.Paste" user "Package Geometry/Pastemask Bottom")
		(5 "F.SilkS" user "Ref Des/Silkscreen Top")
		(7 "B.SilkS" user "Ref Des/Silkscreen Bottom")
		(1 "F.Mask" user "Board Geometry/Soldermask Top")
		(3 "B.Mask" user "Board Geometry/Soldermask Bottom")
		(17 "Dwgs.User" user "User.Drawings")
		(19 "Cmts.User" user "User.Comments")
		(21 "Eco1.User" user "User.Eco1")
		(23 "Eco2.User" user "User.Eco2")
		(25 "Edge.Cuts" user "Board Geometry/Outline")
		(27 "Margin" user)
		(31 "F.CrtYd" user "Package Geometry/Place Bound Top")
		(29 "B.CrtYd" user "Package Geometry/Place Bound Bottom")
		(35 "F.Fab" user "Ref Des/Assembly Top")
		(33 "B.Fab" user "Ref Des/Assembly Bottom")
	)
	(footprint ""
		(layer "F.Cu")
		(at 359.867962 -258.880102 180)
		(property "Reference" "U25"
			(at -45.78477 -62.086744 0)
			(unlocked yes)
			(layer "F.SilkS")
			(effects
				(font
					(size 0.7874 0.5842)
					(thickness 0.1524)
				)
			)
		)
		(property "Value" ""
			(at 0 0 180)
			(layer "F.Fab")
			(effects
				(font
					(size 1.27 1.27)
				)
			)
		)
		(duplicate_pad_numbers_are_jumpers no)
		(pad "P72" smd circle
			(at 32.109918 -26.28011 180)
			(size 0.450088 0.450088)
			(layers "F.Cu" "F.Mask" "F.Paste")
			(net "M_A_CPU0_SA_DQS_DN<6>")
		)
		(pad "P73" smd circle
			(at 33.049972 -26.28011 180)
			(size 0.450088 0.450088)
			(layers "F.Cu" "F.Mask" "F.Paste")
			(net "GND")
		)
		(pad "P74" smd circle
			(at 33.990026 -26.28011 180)
			(size 0.450088 0.450088)
			(layers "F.Cu" "F.Mask" "F.Paste")
			(net "M_A_CPU0_SA_DQS_DN<1>")
		)
		(pad "R1" smd circle
			(at -34.159952 -25.470104 180)
			(size 0.450088 0.450088)
			(layers "F.Cu" "F.Mask" "F.Paste")
			(net "GND")
		)
		(pad "R2" smd circle
			(at -33.219898 -25.470104 180)
			(size 0.450088 0.450088)
			(layers "F.Cu" "F.Mask" "F.Paste")
			(net "M_G_CPU0_SA_DQ<12>")
		)
		(pad "R3" smd circle
			(at -32.280098 -25.470104 180)
			(size 0.450088 0.450088)
			(layers "F.Cu" "F.Mask" "F.Paste")
			(net "M_G_CPU0_SA_DQS_DP<6>")
		)
		(pad "R4" smd circle
			(at -31.340044 -25.470104 180)
			(size 0.450088 0.450088)
			(layers "F.Cu" "F.Mask" "F.Paste")
			(net "GND")
		)
		(pad "R5" smd circle
			(at -30.39999 -25.470104 180)
			(size 0.450088 0.450088)
			(layers "F.Cu" "F.Mask" "F.Paste")
			(net "M_K_CPU0_SA_DQ<12>")
		)
		(pad "R6" smd circle
			(at -29.459936 -25.470104 180)
			(size 0.450088 0.450088)
			(layers "F.Cu" "F.Mask" "F.Paste")
			(net "GND")
		)
		(pad "R7" smd circle
			(at -28.519882 -25.470104 180)
			(size 0.450088 0.450088)
			(layers "F.Cu" "F.Mask" "F.Paste")
			(net "M_K_CPU0_SA_DQS_DP<6>")
		)
		(pad "R8" smd circle
			(at -27.580082 -25.470104 180)
			(size 0.450088 0.450088)
			(layers "F.Cu" "F.Mask" "F.Paste")
			(net "GND")
		)
		(pad "R9" smd circle
			(at -26.640028 -25.470104 180)
			(size 0.450088 0.450088)
			(layers "F.Cu" "F.Mask" "F.Paste")
			(net "M_L_CPU0_SA_DQ<12>")
		)
		(pad "R10" smd circle
			(at -25.699974 -25.470104 180)
			(size 0.450088 0.450088)
			(layers "F.Cu" "F.Mask" "F.Paste")
			(net "M_L_CPU0_SA_DQS_DP<6>")
		)
		(pad "R11" smd circle
			(at -24.75992 -25.470104 180)
			(size 0.450088 0.450088)
			(layers "F.Cu" "F.Mask" "F.Paste")
			(net "GND")
		)
		(pad "R12" smd circle
			(at -23.82012 -25.470104 180)
			(size 0.450088 0.450088)
			(layers "F.Cu" "F.Mask" "F.Paste")
			(net "M_H_CPU0_SA_DQ<12>")
		)
		(pad "R13" smd circle
			(at -22.880066 -25.470104 180)
			(size 0.450088 0.450088)
			(layers "F.Cu" "F.Mask" "F.Paste")
			(net "GND")
		)
		(pad "R14" smd circle
			(at -21.940012 -25.470104 180)
			(size 0.450088 0.450088)
			(layers "F.Cu" "F.Mask" "F.Paste")
			(net "M_H_CPU0_SA_DQS_DP<6>")
		)
		(pad "R15" smd circle
			(at -20.999958 -25.470104 180)
			(size 0.450088 0.450088)
			(layers "F.Cu" "F.Mask" "F.Paste")
			(net "GND")
		)
		(pad "R16" smd circle
			(at -20.059904 -25.470104 180)
			(size 0.450088 0.450088)
			(layers "F.Cu" "F.Mask" "F.Paste")
			(net "M_J_CPU0_SA_DQ<12>")
		)
		(pad "R17" smd circle
			(at -19.120104 -25.470104 180)
			(size 0.450088 0.450088)
			(layers "F.Cu" "F.Mask" "F.Paste")
			(net "M_J_CPU0_SA_DQS_DP<6>")
		)
		(pad "R18" smd circle
			(at -18.18005 -25.470104 180)
			(size 0.450088 0.450088)
			(layers "F.Cu" "F.Mask" "F.Paste")
			(net "GND")
		)
		(pad "R19" smd circle
			(at -17.239996 -25.470104 180)
			(size 0.450088 0.450088)
			(layers "F.Cu" "F.Mask" "F.Paste")
			(net "M_I_CPU0_SA_DQ<12>")
		)
		(pad "R20" smd circle
			(at -16.299942 -25.470104 180)
			(size 0.450088 0.450088)
			(layers "F.Cu" "F.Mask" "F.Paste")
			(net "GND")
		)
		(pad "R21" smd circle
			(at -15.359888 -25.470104 180)
			(size 0.450088 0.450088)
			(layers "F.Cu" "F.Mask" "F.Paste")
			(net "M_I_CPU0_SA_DQS_DP<6>")
		)
		(pad "R22" smd circle
			(at -14.420088 -25.470104 180)
			(size 0.450088 0.450088)
			(layers "F.Cu" "F.Mask" "F.Paste")
			(net "GND")
		)
		(pad "R23" smd circle
			(at -13.480034 -25.470104 180)
			(size 0.450088 0.450088)
			(layers "F.Cu" "F.Mask" "F.Paste")
			(net "P5E_CPU0_G3_TX_DP<1>")
		)
		(pad "R24" smd circle
			(at -12.53998 -25.470104 180)
			(size 0.450088 0.450088)
			(layers "F.Cu" "F.Mask" "F.Paste")
			(net "P5E_CPU0_G3_TX_DN<1>")
		)
		(pad "R25" smd circle
			(at -11.599926 -25.470104 180)
			(size 0.450088 0.450088)
			(layers "F.Cu" "F.Mask" "F.Paste")
			(net "GND")
		)
		(pad "R26" smd circle
			(at -10.659872 -25.470104 180)
			(size 0.450088 0.450088)
			(layers "F.Cu" "F.Mask" "F.Paste")
			(net "P5E_CPU0_G3_TX_DP<4>")
		)
		(pad "R27" smd circle
			(at -9.720072 -25.470104 180)
			(size 0.450088 0.450088)
			(layers "F.Cu" "F.Mask" "F.Paste")
			(net "P5E_CPU0_G3_TX_DN<4>")
		)
		(pad "R28" smd circle
			(at -8.780018 -25.470104 180)
			(size 0.450088 0.450088)
			(layers "F.Cu" "F.Mask" "F.Paste")
			(net "GND")
		)
		(pad "R29" smd circle
			(at -7.839964 -25.470104 180)
			(size 0.450088 0.450088)
			(layers "F.Cu" "F.Mask" "F.Paste")
			(net "P5E_CPU0_G3_TX_DP<7>")
		)
		(pad "R30" smd circle
			(at -6.89991 -25.470104 180)
			(size 0.450088 0.450088)
			(layers "F.Cu" "F.Mask" "F.Paste")
			(net "P5E_CPU0_G3_TX_DN<7>")
		)
		(pad "R31" smd circle
			(at -5.96011 -25.470104 180)
			(size 0.450088 0.450088)
			(layers "F.Cu" "F.Mask" "F.Paste")
			(net "GND")
		)
		(pad "R32" smd circle
			(at -5.020056 -25.470104 180)
			(size 0.450088 0.450088)
			(layers "F.Cu" "F.Mask" "F.Paste")
			(net "P5E_CPU0_G3_TX_DP<10>")
		)
		(pad "R33" smd circle
			(at -4.080002 -25.470104 180)
			(size 0.450088 0.450088)
			(layers "F.Cu" "F.Mask" "F.Paste")
			(net "P5E_CPU0_G3_TX_DN<10>")
		)
		(pad "R34" smd circle
			(at -3.139948 -25.470104 180)
			(size 0.450088 0.450088)
			(layers "F.Cu" "F.Mask" "F.Paste")
			(net "GND")
		)
		(pad "R35" smd circle
			(at -2.199894 -25.470104 180)
			(size 0.450088 0.450088)
			(layers "F.Cu" "F.Mask" "F.Paste")
			(net "GND")
		)
		(pad "R36" smd circle
			(at -1.260094 -25.470104 180)
			(size 0.450088 0.450088)
			(layers "F.Cu" "F.Mask" "F.Paste")
			(net "GND")
		)
		(pad "R40" smd circle
			(at 1.560068 -25.470104 180)
			(size 0.450088 0.450088)
			(layers "F.Cu" "F.Mask" "F.Paste")
			(net "GND")
		)
		(pad "R41" smd circle
			(at 2.500122 -25.470104 180)
			(size 0.450088 0.450088)
			(layers "F.Cu" "F.Mask" "F.Paste")
			(net "GND")
		)
		(pad "R42" smd circle
			(at 3.439922 -25.470104 180)
			(size 0.450088 0.450088)
			(layers "F.Cu" "F.Mask" "F.Paste")
			(net "GND")
		)
		(pad "R43" smd circle
			(at 4.379976 -25.470104 180)
			(size 0.450088 0.450088)
			(layers "F.Cu" "F.Mask" "F.Paste")
			(net "GMI_CPU1_G3_CPU0_G1_TX_DN<5>")
		)
		(pad "R44" smd circle
			(at 5.32003 -25.470104 180)
			(size 0.450088 0.450088)
			(layers "F.Cu" "F.Mask" "F.Paste")
			(net "GMI_CPU1_G3_CPU0_G1_TX_DP<5>")
		)
		(pad "R45" smd circle
			(at 6.260084 -25.470104 180)
			(size 0.450088 0.450088)
			(layers "F.Cu" "F.Mask" "F.Paste")
			(net "GND")
		)
		(pad "R46" smd circle
			(at 7.199884 -25.470104 180)
			(size 0.450088 0.450088)
			(layers "F.Cu" "F.Mask" "F.Paste")
			(net "GMI_CPU1_G3_CPU0_G1_TX_DN<8>")
		)
		(pad "R47" smd circle
			(at 8.139938 -25.470104 180)
			(size 0.450088 0.450088)
			(layers "F.Cu" "F.Mask" "F.Paste")
			(net "GMI_CPU1_G3_CPU0_G1_TX_DP<8>")
		)
		(pad "R48" smd circle
			(at 9.079992 -25.470104 180)
			(size 0.450088 0.450088)
			(layers "F.Cu" "F.Mask" "F.Paste")
			(net "GND")
		)
		(pad "R49" smd circle
			(at 10.020046 -25.470104 180)
			(size 0.450088 0.450088)
			(layers "F.Cu" "F.Mask" "F.Paste")
			(net "GMI_CPU1_G3_CPU0_G1_TX_DN<11>")
		)
		(pad "R50" smd circle
			(at 10.9601 -25.470104 180)
			(size 0.450088 0.450088)
			(layers "F.Cu" "F.Mask" "F.Paste")
			(net "GMI_CPU1_G3_CPU0_G1_TX_DP<11>")
		)
		(pad "R51" smd circle
			(at 11.8999 -25.470104 180)
			(size 0.450088 0.450088)
			(layers "F.Cu" "F.Mask" "F.Paste")
			(net "GND")
		)
		(pad "R52" smd circle
			(at 12.839954 -25.470104 180)
			(size 0.450088 0.450088)
			(layers "F.Cu" "F.Mask" "F.Paste")
			(net "GMI_CPU1_G3_CPU0_G1_TX_DN<14>")
		)
		(pad "R53" smd circle
			(at 13.780008 -25.470104 180)
			(size 0.450088 0.450088)
			(layers "F.Cu" "F.Mask" "F.Paste")
			(net "GMI_CPU1_G3_CPU0_G1_TX_DP<14>")
		)
		(pad "R54" smd circle
			(at 14.720062 -25.470104 180)
			(size 0.450088 0.450088)
			(layers "F.Cu" "F.Mask" "F.Paste")
			(net "GND")
		)
		(pad "R55" smd circle
			(at 15.660116 -25.470104 180)
			(size 0.450088 0.450088)
			(layers "F.Cu" "F.Mask" "F.Paste")
			(net "M_C_CPU0_SA_DQS_DP<6>")
		)
		(pad "R56" smd circle
			(at 16.599916 -25.470104 180)
			(size 0.450088 0.450088)
			(layers "F.Cu" "F.Mask" "F.Paste")
			(net "GND")
		)
		(pad "R57" smd circle
			(at 17.53997 -25.470104 180)
			(size 0.450088 0.450088)
			(layers "F.Cu" "F.Mask" "F.Paste")
			(net "M_C_CPU0_SA_DQ<12>")
		)
		(pad "R58" smd circle
			(at 18.480024 -25.470104 180)
			(size 0.450088 0.450088)
			(layers "F.Cu" "F.Mask" "F.Paste")
			(net "GND")
		)
		(pad "R59" smd circle
			(at 19.420078 -25.470104 180)
			(size 0.450088 0.450088)
			(layers "F.Cu" "F.Mask" "F.Paste")
			(net "M_D_CPU0_SA_DQS_DP<6>")
		)
		(pad "R60" smd circle
			(at 20.359878 -25.470104 180)
			(size 0.450088 0.450088)
			(layers "F.Cu" "F.Mask" "F.Paste")
			(net "M_D_CPU0_SA_DQ<12>")
		)
		(pad "R61" smd circle
			(at 21.299932 -25.470104 180)
			(size 0.450088 0.450088)
			(layers "F.Cu" "F.Mask" "F.Paste")
			(net "GND")
		)
		(pad "R62" smd circle
			(at 22.239986 -25.470104 180)
			(size 0.450088 0.450088)
			(layers "F.Cu" "F.Mask" "F.Paste")
			(net "M_B_CPU0_SA_DQS_DP<6>")
		)
		(pad "R63" smd circle
			(at 23.18004 -25.470104 180)
			(size 0.450088 0.450088)
			(layers "F.Cu" "F.Mask" "F.Paste")
			(net "GND")
		)
		(pad "R64" smd circle
			(at 24.120094 -25.470104 180)
			(size 0.450088 0.450088)
			(layers "F.Cu" "F.Mask" "F.Paste")
			(net "M_B_CPU0_SA_DQ<12>")
		)
		(pad "R65" smd circle
			(at 25.059894 -25.470104 180)
			(size 0.450088 0.450088)
			(layers "F.Cu" "F.Mask" "F.Paste")
			(net "GND")
		)
		(pad "R66" smd circle
			(at 25.999948 -25.470104 180)
			(size 0.450088 0.450088)
			(layers "F.Cu" "F.Mask" "F.Paste")
			(net "M_F_CPU0_SA_DQS_DP<6>")
		)
		(pad "R67" smd circle
			(at 26.940002 -25.470104 180)
			(size 0.450088 0.450088)
			(layers "F.Cu" "F.Mask" "F.Paste")
			(net "M_F_CPU0_SA_DQ<12>")
		)
		(pad "R68" smd circle
			(at 27.880056 -25.470104 180)
			(size 0.450088 0.450088)
			(layers "F.Cu" "F.Mask" "F.Paste")
			(net "GND")
		)
		(pad "R69" smd circle
			(at 28.82011 -25.470104 180)
			(size 0.450088 0.450088)
			(layers "F.Cu" "F.Mask" "F.Paste")
			(net "M_E_CPU0_SA_DQS_DP<6>")
		)
		(pad "R70" smd circle
			(at 29.75991 -25.470104 180)
			(size 0.450088 0.450088)
			(layers "F.Cu" "F.Mask" "F.Paste")
			(net "GND")
		)
		(pad "R71" smd circle
			(at 30.699964 -25.470104 180)
			(size 0.450088 0.450088)
			(layers "F.Cu" "F.Mask" "F.Paste")
			(net "M_E_CPU0_SA_DQ<12>")
		)
		(pad "R72" smd circle
			(at 31.640018 -25.470104 180)
			(size 0.450088 0.450088)
			(layers "F.Cu" "F.Mask" "F.Paste")
			(net "GND")
		)
		(pad "R73" smd circle
			(at 32.580072 -25.470104 180)
			(size 0.450088 0.450088)
			(layers "F.Cu" "F.Mask" "F.Paste")
			(net "M_A_CPU0_SA_DQS_DP<6>")
		)
		(pad "R74" smd circle
			(at 33.519872 -25.470104 180)
			(size 0.450088 0.450088)
			(layers "F.Cu" "F.Mask" "F.Paste")
			(net "M_A_CPU0_SA_DQ<12>")
		)
		(pad "R75" smd circle
			(at 34.459926 -25.470104 180)
			(size 0.450088 0.450088)
			(layers "F.Cu" "F.Mask" "F.Paste")
			(net "GND")
		)
		(pad "T2" smd circle
			(at -33.690052 -24.660098 180)
			(size 0.450088 0.450088)
			(layers "F.Cu" "F.Mask" "F.Paste")
			(net "M_G_CPU0_SA_DQ<14>")
		)
		(pad "T3" smd circle
			(at -32.749998 -24.660098 180)
			(size 0.450088 0.450088)
			(layers "F.Cu" "F.Mask" "F.Paste")
			(net "GND")
		)
		(pad "T4" smd circle
			(at -31.809944 -24.660098 180)
			(size 0.450088 0.450088)
			(layers "F.Cu" "F.Mask" "F.Paste")
			(net "M_G_CPU0_SA_DQ<13>")
		)
		(pad "T5" smd circle
			(at -30.86989 -24.660098 180)
			(size 0.450088 0.450088)
			(layers "F.Cu" "F.Mask" "F.Paste")
			(net "GND")
		)
		(pad "T6" smd circle
			(at -29.93009 -24.660098 180)
			(size 0.450088 0.450088)
			(layers "F.Cu" "F.Mask" "F.Paste")
			(net "M_K_CPU0_SA_DQ<14>")
		)
		(pad "T7" smd circle
			(at -28.990036 -24.660098 180)
			(size 0.450088 0.450088)
			(layers "F.Cu" "F.Mask" "F.Paste")
			(net "M_K_CPU0_SA_DQ<13>")
		)
		(pad "T8" smd circle
			(at -28.049982 -24.660098 180)
			(size 0.450088 0.450088)
			(layers "F.Cu" "F.Mask" "F.Paste")
			(net "GND")
		)
		(pad "T9" smd circle
			(at -27.109928 -24.660098 180)
			(size 0.450088 0.450088)
			(layers "F.Cu" "F.Mask" "F.Paste")
			(net "M_L_CPU0_SA_DQ<14>")
		)
		(pad "T10" smd circle
			(at -26.170128 -24.660098 180)
			(size 0.450088 0.450088)
			(layers "F.Cu" "F.Mask" "F.Paste")
			(net "GND")
		)
		(pad "T11" smd circle
			(at -25.230074 -24.660098 180)
			(size 0.450088 0.450088)
			(layers "F.Cu" "F.Mask" "F.Paste")
			(net "M_L_CPU0_SA_DQ<13>")
		)
		(pad "T12" smd circle
			(at -24.29002 -24.660098 180)
			(size 0.450088 0.450088)
			(layers "F.Cu" "F.Mask" "F.Paste")
			(net "GND")
		)
		(pad "T13" smd circle
			(at -23.349966 -24.660098 180)
			(size 0.450088 0.450088)
			(layers "F.Cu" "F.Mask" "F.Paste")
			(net "M_H_CPU0_SA_DQ<14>")
		)
		(pad "T14" smd circle
			(at -22.409912 -24.660098 180)
			(size 0.450088 0.450088)
			(layers "F.Cu" "F.Mask" "F.Paste")
			(net "M_H_CPU0_SA_DQ<13>")
		)
		(pad "T15" smd circle
			(at -21.470112 -24.660098 180)
			(size 0.450088 0.450088)
			(layers "F.Cu" "F.Mask" "F.Paste")
			(net "GND")
		)
		(pad "T16" smd circle
			(at -20.530058 -24.660098 180)
			(size 0.450088 0.450088)
			(layers "F.Cu" "F.Mask" "F.Paste")
			(net "M_J_CPU0_SA_DQ<14>")
		)
		(pad "T17" smd circle
			(at -19.590004 -24.660098 180)
			(size 0.450088 0.450088)
			(layers "F.Cu" "F.Mask" "F.Paste")
			(net "GND")
		)
		(pad "T18" smd circle
			(at -18.64995 -24.660098 180)
			(size 0.450088 0.450088)
			(layers "F.Cu" "F.Mask" "F.Paste")
			(net "M_J_CPU0_SA_DQ<13>")
		)
		(pad "T19" smd circle
			(at -17.709896 -24.660098 180)
			(size 0.450088 0.450088)
			(layers "F.Cu" "F.Mask" "F.Paste")
			(net "GND")
		)
		(pad "T20" smd circle
			(at -16.770096 -24.660098 180)
			(size 0.450088 0.450088)
			(layers "F.Cu" "F.Mask" "F.Paste")
			(net "M_I_CPU0_SA_DQ<14>")
		)
		(pad "T21" smd circle
			(at -15.830042 -24.660098 180)
			(size 0.450088 0.450088)
			(layers "F.Cu" "F.Mask" "F.Paste")
			(net "M_I_CPU0_SA_DQ<13>")
		)
		(pad "T22" smd circle
			(at -14.889988 -24.660098 180)
			(size 0.450088 0.450088)
			(layers "F.Cu" "F.Mask" "F.Paste")
			(net "GND")
		)
		(pad "T23" smd circle
			(at -13.949934 -24.660098 180)
			(size 0.450088 0.450088)
			(layers "F.Cu" "F.Mask" "F.Paste")
			(net "PVDDCR_CPU0_P0")
		)
		(pad "T24" smd circle
			(at -13.00988 -24.660098 180)
			(size 0.450088 0.450088)
			(layers "F.Cu" "F.Mask" "F.Paste")
			(net "PVDDCR_CPU0_P0")
		)
		(pad "T25" smd circle
			(at -12.07008 -24.660098 180)
			(size 0.450088 0.450088)
			(layers "F.Cu" "F.Mask" "F.Paste")
			(net "GND")
		)
		(pad "T26" smd circle
			(at -11.130026 -24.660098 180)
			(size 0.450088 0.450088)
			(layers "F.Cu" "F.Mask" "F.Paste")
			(net "PVDDCR_CPU0_P0")
		)
		(pad "T27" smd circle
			(at -10.189972 -24.660098 180)
			(size 0.450088 0.450088)
			(layers "F.Cu" "F.Mask" "F.Paste")
			(net "PVDDCR_CPU0_P0")
		)
		(pad "T28" smd circle
			(at -9.249918 -24.660098 180)
			(size 0.450088 0.450088)
			(layers "F.Cu" "F.Mask" "F.Paste")
			(net "GND")
		)
		(pad "T29" smd circle
			(at -8.310118 -24.660098 180)
			(size 0.450088 0.450088)
			(layers "F.Cu" "F.Mask" "F.Paste")
			(net "PVDDCR_CPU0_P0")
		)
		(pad "T30" smd circle
			(at -7.370064 -24.660098 180)
			(size 0.450088 0.450088)
			(layers "F.Cu" "F.Mask" "F.Paste")
			(net "PVDDCR_CPU0_P0")
		)
		(pad "T31" smd circle
			(at -6.43001 -24.660098 180)
			(size 0.450088 0.450088)
			(layers "F.Cu" "F.Mask" "F.Paste")
			(net "GND")
		)
		(pad "T32" smd circle
			(at -5.489956 -24.660098 180)
			(size 0.450088 0.450088)
			(layers "F.Cu" "F.Mask" "F.Paste")
			(net "PVDDCR_CPU0_P0")
		)
		(pad "T33" smd circle
			(at -4.549902 -24.660098 180)
			(size 0.450088 0.450088)
			(layers "F.Cu" "F.Mask" "F.Paste")
			(net "PVDDCR_CPU0_P0")
		)
		(pad "T34" smd circle
			(at -3.610102 -24.660098 180)
			(size 0.450088 0.450088)
			(layers "F.Cu" "F.Mask" "F.Paste")
			(net "GND")
		)
		(pad "T35" smd circle
			(at -2.670048 -24.660098 180)
			(size 0.450088 0.450088)
			(layers "F.Cu" "F.Mask" "F.Paste")
			(net "P5E_CPU0_G3_TX_DP<14>")
		)
	)
)
